(kicad_pcb
	(version 20260206)
	(generator "pcbnew")
	(generator_version "10.0")
	(general
		(thickness 1.6)
		(legacy_teardrops no)
	)
	(paper "A4")
	(title_block
		(title "panther-plus-userver — 13130-1b_20150205.brd")
		(comment 1 "Honey Badger (Wiwynn) / footprints 744-749 of 1509")
	)
	(layers
		(0 "F.Cu" signal "TOP")
		(4 "In1.Cu" signal "L2")
		(6 "In2.Cu" signal "L3")
		(8 "In3.Cu" signal "L4")
		(10 "In4.Cu" signal "L5")
		(12 "In5.Cu" signal "L6")
		(14 "In6.Cu" signal "L7")
		(16 "In7.Cu" signal "L8")
		(18 "In8.Cu" signal "L9")
		(20 "In9.Cu" signal "L10")
		(22 "In10.Cu" signal "L11")
		(2 "B.Cu" signal "BOTTOM")
		(9 "F.Adhes" user "F.Adhesive")
		(11 "B.Adhes" user "B.Adhesive")
		(13 "F.Paste" user "Package Geometry/Pastemask Top")
		(15 "B.Paste" user "Package Geometry/Pastemask Bottom")
		(5 "F.SilkS" user "Ref Des/Silkscreen Top")
		(7 "B.SilkS" user "Ref Des/Silkscreen Bottom")
		(1 "F.Mask" user "Board Geometry/Soldermask Top")
		(3 "B.Mask" user "Board Geometry/Soldermask Bottom")
		(17 "Dwgs.User" user "User.Drawings")
		(19 "Cmts.User" user "User.Comments")
		(21 "Eco1.User" user "User.Eco1")
		(23 "Eco2.User" user "User.Eco2")
		(25 "Edge.Cuts" user "Board Geometry/Outline")
		(27 "Margin" user)
		(31 "F.CrtYd" user "Package Geometry/Place Bound Top")
		(29 "B.CrtYd" user "Package Geometry/Place Bound Bottom")
		(35 "F.Fab" user "Ref Des/Assembly Top")
		(33 "B.Fab" user "Ref Des/Assembly Bottom")
	)
	(footprint ""
		(layer "F.Cu")
		(at 64.262 -33.02 90)
		(property "Reference" "R239"
			(at 0 0 90)
			(layer "F.SilkS")
			(hide yes)
			(effects
				(font
					(size 1.27 1.27)
				)
			)
		)
		(property "Value" "1KR2F-3-GP"
			(at 0.064008 -3.993896 90)
			(unlocked yes)
			(layer "F.Fab")
			(hide yes)
			(effects
				(font
					(size 1.016 1.016)
					(thickness 0.1524)
				)
			)
		)
		(property "Device Type" "R402H16"
			(at 0.064008 -5.517896 90)
			(unlocked yes)
			(layer "F.Fab")
			(hide yes)
			(effects
				(font
					(size 1.016 1.016)
					(thickness 0.1524)
				)
			)
		)
		(duplicate_pad_numbers_are_jumpers no)
		(fp_rect
			(start -0.381 0.8382)
			(end 0.381 -0.8382)
			(stroke
				(width 0)
				(type default)
			)
			(fill no)
			(layer "F.CrtYd")
		)
		(fp_rect
			(start -0.381 0.8382)
			(end 0.381 -0.8382)
			(stroke
				(width 0)
				(type default)
			)
			(fill no)
			(layer "F.Fab")
		)
		(pad "1" smd custom
			(at 0 -0.4318 90)
			(size 0.127 0.127)
			(layers "F.Cu" "F.Mask" "F.Paste")
			(net "GND")
			(options
				(clearance outline)
				(anchor circle)
			)
			(primitives
				(gr_poly
					(pts
						(arc
							(start -0.2032 -0.2794)
							(mid -0.239121 -0.264521)
							(end -0.254 -0.2286)
						)
						(arc
							(start -0.254 0.2286)
							(mid -0.239121 0.264521)
							(end -0.2032 0.2794)
						)
						(arc
							(start 0.2032 0.2794)
							(mid 0.239121 0.264521)
							(end 0.254 0.2286)
						)
						(arc
							(start 0.254 -0.2286)
							(mid 0.239121 -0.264521)
							(end 0.2032 -0.2794)
						)
					)
					(width 0)
					(fill yes)
				)
			)
		)
		(pad "2" smd custom
			(at 0 0.4318 90)
			(size 0.127 0.127)
			(layers "F.Cu" "F.Mask" "F.Paste")
			(net "P1V8")
			(options
				(clearance outline)
				(anchor circle)
			)
			(primitives
				(gr_poly
					(pts
						(arc
							(start -0.2032 -0.2794)
							(mid -0.239121 -0.264521)
							(end -0.254 -0.2286)
						)
						(arc
							(start -0.254 0.2286)
							(mid -0.239121 0.264521)
							(end -0.2032 0.2794)
						)
						(arc
							(start 0.2032 0.2794)
							(mid 0.239121 0.264521)
							(end 0.254 0.2286)
						)
						(arc
							(start 0.254 -0.2286)
							(mid 0.239121 -0.264521)
							(end 0.2032 -0.2794)
						)
					)
					(width 0)
					(fill yes)
				)
			)
		)
	)
	(footprint ""
		(layer "F.Cu")
		(at 55.245 -39.878 -90)
		(property "Reference" "R88"
			(at 0 0 270)
			(layer "F.SilkS")
			(hide yes)
			(effects
				(font
					(size 1.27 1.27)
				)
			)
		)
		(property "Value" "1KR2F-3-GP"
			(at 0.064008 -3.993896 270)
			(unlocked yes)
			(layer "F.Fab")
			(hide yes)
			(effects
				(font
					(size 1.016 1.016)
					(thickness 0.1524)
				)
			)
		)
		(property "Device Type" "R402H16"
			(at 0.064008 -5.517896 270)
			(unlocked yes)
			(layer "F.Fab")
			(hide yes)
			(effects
				(font
					(size 1.016 1.016)
					(thickness 0.1524)
				)
			)
		)
		(duplicate_pad_numbers_are_jumpers no)
		(fp_rect
			(start -0.381 0.8382)
			(end 0.381 -0.8382)
			(stroke
				(width 0)
				(type default)
			)
			(fill no)
			(layer "F.CrtYd")
		)
		(fp_rect
			(start -0.381 0.8382)
			(end 0.381 -0.8382)
			(stroke
				(width 0)
				(type default)
			)
			(fill no)
			(layer "F.Fab")
		)
		(pad "1" smd custom
			(at 0 -0.4318 270)
			(size 0.127 0.127)
			(layers "F.Cu" "F.Mask" "F.Paste")
			(net "GND")
			(options
				(clearance outline)
				(anchor circle)
			)
			(primitives
				(gr_poly
					(pts
						(arc
							(start -0.2032 -0.2794)
							(mid -0.239121 -0.264521)
							(end -0.254 -0.2286)
						)
						(arc
							(start -0.254 0.2286)
							(mid -0.239121 0.264521)
							(end -0.2032 0.2794)
						)
						(arc
							(start 0.2032 0.2794)
							(mid 0.239121 0.264521)
							(end 0.254 0.2286)
						)
						(arc
							(start 0.254 -0.2286)
							(mid 0.239121 -0.264521)
							(end 0.2032 -0.2794)
						)
					)
					(width 0)
					(fill yes)
				)
			)
		)
		(pad "2" smd custom
			(at 0 0.4318 270)
			(size 0.127 0.127)
			(layers "F.Cu" "F.Mask" "F.Paste")
			(net "P3V3")
			(options
				(clearance outline)
				(anchor circle)
			)
			(primitives
				(gr_poly
					(pts
						(arc
							(start -0.2032 -0.2794)
							(mid -0.239121 -0.264521)
							(end -0.254 -0.2286)
						)
						(arc
							(start -0.254 0.2286)
							(mid -0.239121 0.264521)
							(end -0.2032 0.2794)
						)
						(arc
							(start 0.2032 0.2794)
							(mid 0.239121 0.264521)
							(end 0.254 0.2286)
						)
						(arc
							(start 0.254 -0.2286)
							(mid 0.239121 -0.264521)
							(end 0.2032 -0.2794)
						)
					)
					(width 0)
					(fill yes)
				)
			)
		)
	)
	(footprint ""
		(layer "F.Cu")
		(at 8.509 -65.405 90)
		(property "Reference" "C181"
			(at 0 0 90)
			(layer "F.SilkS")
			(hide yes)
			(effects
				(font
					(size 1.27 1.27)
				)
			)
		)
		(property "Value" "SCD1U16V2KX-3GP"
			(at 1.1811 -2.7051 90)
			(unlocked yes)
			(layer "F.Fab")
			(hide yes)
			(effects
				(font
					(size 1.016 1.016)
					(thickness 0.1524)
				)
			)
		)
		(property "Device Type" "C402H22"
			(at 1.1811 -4.2291 90)
			(unlocked yes)
			(layer "F.Fab")
			(hide yes)
			(effects
				(font
					(size 1.016 1.016)
					(thickness 0.1524)
				)
			)
		)
		(duplicate_pad_numbers_are_jumpers no)
		(fp_rect
			(start -0.381 0.7366)
			(end 0.381 -0.7366)
			(stroke
				(width 0)
				(type default)
			)
			(fill no)
			(layer "F.CrtYd")
		)
		(fp_rect
			(start -0.381 0.7366)
			(end 0.381 -0.7366)
			(stroke
				(width 0)
				(type default)
			)
			(fill no)
			(layer "F.Fab")
		)
		(pad "1" smd custom
			(at 0 -0.4572 90)
			(size 0.1143 0.1143)
			(layers "F.Cu" "F.Mask" "F.Paste")
			(net "P2E_CPU_NGFF_C_RX_DN15")
			(options
				(clearance outline)
				(anchor circle)
			)
			(primitives
				(gr_poly
					(pts
						(arc
							(start -0.254 -0.1778)
							(mid -0.239121 -0.213721)
							(end -0.2032 -0.2286)
						)
						(arc
							(start 0.2032 -0.2286)
							(mid 0.239121 -0.213721)
							(end 0.254 -0.1778)
						)
						(arc
							(start 0.254 0.1778)
							(mid 0.239121 0.213721)
							(end 0.2032 0.2286)
						)
						(arc
							(start -0.2032 0.2286)
							(mid -0.239121 0.213721)
							(end -0.254 0.1778)
						)
					)
					(width 0)
					(fill yes)
				)
			)
		)
		(pad "2" smd custom
			(at 0 0.4572 90)
			(size 0.1143 0.1143)
			(layers "F.Cu" "F.Mask" "F.Paste")
			(net "P2E_CPU_NGFF_RX_DN15")
			(options
				(clearance outline)
				(anchor circle)
			)
			(primitives
				(gr_poly
					(pts
						(arc
							(start -0.254 -0.1778)
							(mid -0.239121 -0.213721)
							(end -0.2032 -0.2286)
						)
						(arc
							(start 0.2032 -0.2286)
							(mid 0.239121 -0.213721)
							(end 0.254 -0.1778)
						)
						(arc
							(start 0.254 0.1778)
							(mid 0.239121 0.213721)
							(end 0.2032 0.2286)
						)
						(arc
							(start -0.2032 0.2286)
							(mid -0.239121 0.213721)
							(end -0.254 0.1778)
						)
					)
					(width 0)
					(fill yes)
				)
			)
		)
	)
	(footprint ""
		(layer "F.Cu")
		(at 131.699 -51.689)
		(property "Reference" "R15"
			(at 0 0 0)
			(layer "F.SilkS")
			(hide yes)
			(effects
				(font
					(size 1.27 1.27)
				)
			)
		)
		(property "Value" "0R2J-2-GP"
			(at 1.7907 -1.1176 0)
			(unlocked yes)
			(layer "F.Fab")
			(hide yes)
			(effects
				(font
					(size 1.016 1.016)
					(thickness 0.1524)
				)
			)
		)
		(property "Device Type" "R402H16"
			(at 1.7907 -2.6416 0)
			(unlocked yes)
			(layer "F.Fab")
			(hide yes)
			(effects
				(font
					(size 1.016 1.016)
					(thickness 0.1524)
				)
			)
		)
		(duplicate_pad_numbers_are_jumpers no)
		(fp_rect
			(start -0.381 0.8382)
			(end 0.381 -0.8382)
			(stroke
				(width 0)
				(type default)
			)
			(fill no)
			(layer "F.CrtYd")
		)
		(fp_rect
			(start -0.381 0.8382)
			(end 0.381 -0.8382)
			(stroke
				(width 0)
				(type default)
			)
			(fill no)
			(layer "F.Fab")
		)
		(pad "1" smd custom
			(at 0 -0.4318)
			(size 0.127 0.127)
			(layers "F.Cu" "F.Mask" "F.Paste")
			(net "MEMORY_HOT_LV_R#")
			(options
				(clearance outline)
				(anchor circle)
			)
			(primitives
				(gr_poly
					(pts
						(arc
							(start -0.2032 -0.2794)
							(mid -0.239121 -0.264521)
							(end -0.254 -0.2286)
						)
						(arc
							(start -0.254 0.2286)
							(mid -0.239121 0.264521)
							(end -0.2032 0.2794)
						)
						(arc
							(start 0.2032 0.2794)
							(mid 0.239121 0.264521)
							(end 0.254 0.2286)
						)
						(arc
							(start 0.254 -0.2286)
							(mid 0.239121 -0.264521)
							(end 0.2032 -0.2794)
						)
					)
					(width 0)
					(fill yes)
				)
			)
		)
		(pad "2" smd custom
			(at 0 0.4318)
			(size 0.127 0.127)
			(layers "F.Cu" "F.Mask" "F.Paste")
			(net "MEMORY_HOT_LV_E2#")
			(options
				(clearance outline)
				(anchor circle)
			)
			(primitives
				(gr_poly
					(pts
						(arc
							(start -0.2032 -0.2794)
							(mid -0.239121 -0.264521)
							(end -0.254 -0.2286)
						)
						(arc
							(start -0.254 0.2286)
							(mid -0.239121 0.264521)
							(end -0.2032 0.2794)
						)
						(arc
							(start 0.2032 0.2794)
							(mid 0.239121 0.264521)
							(end 0.254 0.2286)
						)
						(arc
							(start 0.254 -0.2286)
							(mid 0.239121 -0.264521)
							(end 0.2032 -0.2794)
						)
					)
					(width 0)
					(fill yes)
				)
			)
		)
	)
	(footprint ""
		(layer "F.Cu")
		(at 190.4492 -27.5082)
		(property "Reference" "PC106"
			(at 0 0 0)
			(layer "F.SilkS")
			(hide yes)
			(effects
				(font
					(size 1.27 1.27)
				)
			)
		)
		(property "Value" "SC1U16V3KX-5GP"
			(at -0.0254 -2.0193 0)
			(unlocked yes)
			(layer "F.Fab")
			(hide yes)
			(effects
				(font
					(size 1.016 1.016)
					(thickness 0.1524)
				)
			)
		)
		(property "Device Type" "C603H36"
			(at -0.0254 -3.5433 0)
			(unlocked yes)
			(layer "F.Fab")
			(hide yes)
			(effects
				(font
					(size 1.016 1.016)
					(thickness 0.1524)
				)
			)
		)
		(duplicate_pad_numbers_are_jumpers no)
		(fp_line
			(start -0.4064 0)
			(end 0.4064 0)
			(stroke
				(width 0.2286)
				(type default)
			)
			(layer "F.SilkS")
		)
		(fp_rect
			(start -0.635 1.1811)
			(end 0.635 -1.1811)
			(stroke
				(width 0)
				(type default)
			)
			(fill no)
			(layer "F.CrtYd")
		)
		(fp_rect
			(start -0.635 1.1811)
			(end 0.635 -1.1811)
			(stroke
				(width 0)
				(type default)
			)
			(fill no)
			(layer "F.Fab")
		)
		(pad "1" smd custom
			(at 0 -0.6604)
			(size 0.19685 0.19685)
			(layers "F.Cu" "F.Mask" "F.Paste")
			(net "VR_PVDDR_A_VDD")
			(options
				(clearance outline)
				(anchor circle)
			)
			(primitives
				(gr_poly
					(pts
						(arc
							(start 0.508 -0.2921)
							(mid 0.478242 -0.363942)
							(end 0.4064 -0.3937)
						)
						(arc
							(start -0.4064 -0.3937)
							(mid -0.478242 -0.363942)
							(end -0.508 -0.2921)
						)
						(arc
							(start -0.508 0.2921)
							(mid -0.478242 0.363942)
							(end -0.4064 0.3937)
						)
						(arc
							(start 0.4064 0.3937)
							(mid 0.478242 0.363942)
							(end 0.508 0.2921)
						)
					)
					(width 0)
					(fill yes)
				)
			)
		)
		(pad "2" smd custom
			(at 0 0.6604)
			(size 0.19685 0.19685)
			(layers "F.Cu" "F.Mask" "F.Paste")
			(net "GND")
			(options
				(clearance outline)
				(anchor circle)
			)
			(primitives
				(gr_poly
					(pts
						(arc
							(start 0.508 -0.2921)
							(mid 0.478242 -0.363942)
							(end 0.4064 -0.3937)
						)
						(arc
							(start -0.4064 -0.3937)
							(mid -0.478242 -0.363942)
							(end -0.508 -0.2921)
						)
						(arc
							(start -0.508 0.2921)
							(mid -0.478242 0.363942)
							(end -0.4064 0.3937)
						)
						(arc
							(start 0.4064 0.3937)
							(mid 0.478242 0.363942)
							(end 0.508 0.2921)
						)
					)
					(width 0)
					(fill yes)
				)
			)
		)
	)
	(footprint ""
		(layer "F.Cu")
		(at 137.033 -49.657 180)
		(property "Reference" "SW1"
			(at 0 0 180)
			(layer "F.SilkS")
			(hide yes)
			(effects
				(font
					(size 1.27 1.27)
				)
			)
		)
		(property "Value" "SW-PUSH-2P-6-GP"
			(at -3.7973 -1.2573 180)
			(unlocked yes)
			(layer "F.Fab")
			(hide yes)
			(effects
				(font
					(size 1.016 1.016)
					(thickness 0.1524)
				)
			)
		)
		(property "Device Type" "TL1015AF160QG-2"
			(at -3.7973 -2.7813 180)
			(unlocked yes)
			(layer "F.Fab")
			(hide yes)
			(effects
				(font
					(size 1.016 1.016)
					(thickness 0.1524)
				)
			)
		)
		(duplicate_pad_numbers_are_jumpers no)
		(fp_poly
			(pts
				(xy -2.726944 0.01905) (xy -3.29057 0.582676) (xy -3.29057 -0.544576)
			)
			(stroke
				(width 0)
				(type default)
			)
			(fill yes)
			(layer "F.SilkS")
		)
		(fp_poly
			(pts
				(xy -2.2098 1.905) (xy -2.2098 0.8255) (xy -2.6797 0.8255) (xy -2.6797 -0.8255) (xy -2.2098 -0.8255)
				(xy -2.2098 -1.905) (xy 2.2098 -1.905) (xy 2.2098 -0.8255) (xy 2.6797 -0.8255) (xy 2.6797 0.8255)
				(xy 2.2098 0.8255) (xy 2.2098 1.905)
			)
			(stroke
				(width 0)
				(type default)
			)
			(fill no)
			(layer "F.CrtYd")
		)
		(fp_poly
			(pts
				(xy -2.2098 1.905) (xy -2.2098 0.8255) (xy -2.6797 0.8255) (xy -2.6797 -0.8255) (xy -2.2098 -0.8255)
				(xy -2.2098 -1.905) (xy 2.2098 -1.905) (xy 2.2098 -0.8255) (xy 2.6797 -0.8255) (xy 2.6797 0.8255)
				(xy 2.2098 0.8255) (xy 2.2098 1.905)
			)
			(stroke
				(width 0)
				(type default)
			)
			(fill no)
			(layer "F.Fab")
		)
		(pad "1" smd rect
			(at -2.074926 0 180)
			(size 0.9398 1.397)
			(layers "F.Cu" "F.Mask" "F.Paste")
			(net "C_NCONFIG#")
		)
		(pad "2" smd rect
			(at 2.074926 0 180)
			(size 0.9398 1.397)
			(layers "F.Cu" "F.Mask" "F.Paste")
			(net "GND")
		)
		(zone
			(layer "F.Cu")
			(hatch none 0.5)
			(connect_pads
				(clearance 0)
			)
			(min_thickness 0.25)
			(keepout
				(tracks allowed)
				(vias not_allowed)
				(pads allowed)
				(copperpour not_allowed)
				(footprints allowed)
			)
			(placement
				(enabled no)
				(sheetname "")
			)
			(fill
				(thermal_gap 0.5)
				(thermal_bridge_width 0.5)
				(island_removal_mode 0)
			)
			(polygon
				(pts
					(xy 136.033002 -51.55692) (xy 134.88289 -51.55692) (xy 134.88289 -50.807112) (xy 136.033002 -50.807112)
				)
			)
		)
		(zone
			(layer "F.Cu")
			(hatch none 0.5)
			(connect_pads
				(clearance 0)
			)
			(min_thickness 0.25)
			(keepout
				(tracks not_allowed)
				(vias allowed)
				(pads allowed)
				(copperpour not_allowed)
				(footprints allowed)
			)
			(placement
				(enabled no)
				(sheetname "")
			)
			(fill
				(thermal_gap 0.5)
				(thermal_bridge_width 0.5)
				(island_removal_mode 0)
			)
			(polygon
				(pts
					(xy 136.033002 -50.807112) (xy 136.033002 -51.55692) (xy 134.88289 -51.55692) (xy 134.88289 -50.807112)
				)
			)
		)
		(zone
			(layer "F.Cu")
			(hatch none 0.5)
			(connect_pads
				(clearance 0)
			)
			(min_thickness 0.25)
			(keepout
				(tracks allowed)
				(vias not_allowed)
				(pads allowed)
				(copperpour not_allowed)
				(footprints allowed)
			)
			(placement
				(enabled no)
				(sheetname "")
			)
			(fill
				(thermal_gap 0.5)
				(thermal_bridge_width 0.5)
				(island_removal_mode 0)
			)
			(polygon
				(pts
					(xy 136.033002 -48.506888) (xy 134.88289 -48.506888) (xy 134.88289 -47.75708) (xy 136.033002 -47.75708)
				)
			)
		)
		(zone
			(layer "F.Cu")
			(hatch none 0.5)
			(connect_pads
				(clearance 0)
			)
			(min_thickness 0.25)
			(keepout
				(tracks not_allowed)
				(vias allowed)
				(pads allowed)
				(copperpour not_allowed)
				(footprints allowed)
			)
			(placement
				(enabled no)
				(sheetname "")
			)
			(fill
				(thermal_gap 0.5)
				(thermal_bridge_width 0.5)
				(island_removal_mode 0)
			)
			(polygon
				(pts
					(xy 136.033002 -47.75708) (xy 136.033002 -48.506888) (xy 134.88289 -48.506888) (xy 134.88289 -47.75708)
				)
			)
		)
		(zone
			(layer "F.Cu")
			(hatch none 0.5)
			(connect_pads
				(clearance 0)
			)
			(min_thickness 0.25)
			(keepout
				(tracks allowed)
				(vias not_allowed)
				(pads allowed)
				(copperpour not_allowed)
				(footprints allowed)
			)
			(placement
				(enabled no)
				(sheetname "")
			)
			(fill
				(thermal_gap 0.5)
				(thermal_bridge_width 0.5)
				(island_removal_mode 0)
			)
			(polygon
				(pts
					(xy 139.18311 -51.55692) (xy 138.032998 -51.55692) (xy 138.032998 -50.807112) (xy 139.18311 -50.807112)
				)
			)
		)
		(zone
			(layer "F.Cu")
			(hatch none 0.5)
			(connect_pads
				(clearance 0)
			)
			(min_thickness 0.25)
			(keepout
				(tracks not_allowed)
				(vias allowed)
				(pads allowed)
				(copperpour not_allowed)
				(footprints allowed)
			)
			(placement
				(enabled no)
				(sheetname "")
			)
			(fill
				(thermal_gap 0.5)
				(thermal_bridge_width 0.5)
				(island_removal_mode 0)
			)
			(polygon
				(pts
					(xy 139.18311 -50.807112) (xy 139.18311 -51.55692) (xy 138.032998 -51.55692) (xy 138.032998 -50.807112)
				)
			)
		)
		(zone
			(layer "F.Cu")
			(hatch none 0.5)
			(connect_pads
				(clearance 0)
			)
			(min_thickness 0.25)
			(keepout
				(tracks allowed)
				(vias not_allowed)
				(pads allowed)
				(copperpour not_allowed)
				(footprints allowed)
			)
			(placement
				(enabled no)
				(sheetname "")
			)
			(fill
				(thermal_gap 0.5)
				(thermal_bridge_width 0.5)
				(island_removal_mode 0)
			)
			(polygon
				(pts
					(xy 139.18311 -48.506888) (xy 138.032998 -48.506888) (xy 138.032998 -47.75708) (xy 139.18311 -47.75708)
				)
			)
		)
		(zone
			(layer "F.Cu")
			(hatch none 0.5)
			(connect_pads
				(clearance 0)
			)
			(min_thickness 0.25)
			(keepout
				(tracks not_allowed)
				(vias allowed)
				(pads allowed)
				(copperpour not_allowed)
				(footprints allowed)
			)
			(placement
				(enabled no)
				(sheetname "")
			)
			(fill
				(thermal_gap 0.5)
				(thermal_bridge_width 0.5)
				(island_removal_mode 0)
			)
			(polygon
				(pts
					(xy 139.18311 -47.75708) (xy 139.18311 -48.506888) (xy 138.032998 -48.506888) (xy 138.032998 -47.75708)
				)
			)
		)
	)
)
